(kicad_pcb
	(version 20260206)
	(generator "pcbnew")
	(generator_version "10.0")
	(general
		(thickness 1.6)
		(legacy_teardrops no)
	)
	(paper "A4")
	(title_block
		(title "timecard-production-celestica-r4006 — R4006-B0001-02_R01.brd")
		(comment 1 "Time Appliance Project (Time Card) / footprints 53-56 of 1113")
	)
	(layers
		(0 "F.Cu" signal "TOP")
		(4 "In1.Cu" signal "L02_GND1")
		(6 "In2.Cu" signal "L03_SIG1")
		(8 "In3.Cu" signal "L04_GND2")
		(10 "In4.Cu" signal "L05_VCC1")
		(12 "In5.Cu" signal "L06_VCC2")
		(14 "In6.Cu" signal "L07_GND3")
		(16 "In7.Cu" signal "L08_SIG2")
		(18 "In8.Cu" signal "L09_GND4")
		(2 "B.Cu" signal "BOTTOM")
		(9 "F.Adhes" user "F.Adhesive")
		(11 "B.Adhes" user "B.Adhesive")
		(13 "F.Paste" user "Package Geometry/Pastemask Top")
		(15 "B.Paste" user "Package Geometry/Pastemask Bottom")
		(5 "F.SilkS" user "Ref Des/Silkscreen Top")
		(7 "B.SilkS" user "Ref Des/Silkscreen Bottom")
		(1 "F.Mask" user "Board Geometry/Soldermask Top")
		(3 "B.Mask" user "Board Geometry/Soldermask Bottom")
		(17 "Dwgs.User" user "User.Drawings")
		(19 "Cmts.User" user "User.Comments")
		(21 "Eco1.User" user "User.Eco1")
		(23 "Eco2.User" user "User.Eco2")
		(25 "Edge.Cuts" user "Board Geometry/Outline")
		(27 "Margin" user)
		(31 "F.CrtYd" user "Package Geometry/Place Bound Top")
		(29 "B.CrtYd" user "Package Geometry/Place Bound Bottom")
		(35 "F.Fab" user "Ref Des/Assembly Top")
		(33 "B.Fab" user "Ref Des/Assembly Bottom")
	)
	(footprint ""
		(layer "F.Cu")
		(at 54.229 -80.645 -90)
		(property "Reference" "U35"
			(at 0.508 -2.70637 90)
			(unlocked yes)
			(layer "F.SilkS")
			(effects
				(font
					(size 0.7874 0.5842)
					(thickness 0.1524)
				)
			)
		)
		(property "Value" ""
			(at 0 0 270)
			(layer "F.Fab")
			(effects
				(font
					(size 1.27 1.27)
				)
			)
		)
		(property "Device Type" "LM75BDP_TSSOP8-G220-10215-01"
			(at -0.03175 2.55651 270)
			(unlocked yes)
			(layer "F.Fab")
			(hide yes)
			(effects
				(font
					(size 0.7874 0.5842)
					(thickness 0.1524)
				)
			)
		)
		(property "User Part Number" "PARTNUM*"
			(at -0.037592 3.488182 270)
			(unlocked yes)
			(layer "Cmts.User")
			(hide yes)
			(effects
				(font
					(size 0.7874 0.5842)
					(thickness 0.1524)
				)
			)
		)
		(duplicate_pad_numbers_are_jumpers no)
		(fp_line
			(start -1.778 1.778)
			(end 1.778 1.778)
			(stroke
				(width 0.1)
				(type default)
			)
			(layer "F.SilkS")
		)
		(fp_line
			(start 1.778 1.778)
			(end 1.778 1.45796)
			(stroke
				(width 0.1)
				(type default)
			)
			(layer "F.SilkS")
		)
		(fp_line
			(start -3.3147 1.45796)
			(end -1.778 1.45796)
			(stroke
				(width 0.1)
				(type default)
			)
			(layer "F.SilkS")
		)
		(fp_line
			(start -1.778 1.45796)
			(end -1.778 1.778)
			(stroke
				(width 0.1)
				(type default)
			)
			(layer "F.SilkS")
		)
		(fp_line
			(start 1.778 1.45796)
			(end 3.3147 1.45796)
			(stroke
				(width 0.1)
				(type default)
			)
			(layer "F.SilkS")
		)
		(fp_line
			(start 3.3147 1.45796)
			(end 3.3147 -1.45796)
			(stroke
				(width 0.1)
				(type default)
			)
			(layer "F.SilkS")
		)
		(fp_line
			(start -3.3147 -1.45796)
			(end -3.3147 1.45796)
			(stroke
				(width 0.1)
				(type default)
			)
			(layer "F.SilkS")
		)
		(fp_line
			(start -1.778 -1.45796)
			(end -3.3147 -1.45796)
			(stroke
				(width 0.1)
				(type default)
			)
			(layer "F.SilkS")
		)
		(fp_line
			(start 1.778 -1.45796)
			(end 1.778 -1.778)
			(stroke
				(width 0.1)
				(type default)
			)
			(layer "F.SilkS")
		)
		(fp_line
			(start 3.3147 -1.45796)
			(end 1.778 -1.45796)
			(stroke
				(width 0.1)
				(type default)
			)
			(layer "F.SilkS")
		)
		(fp_line
			(start -1.778 -1.778)
			(end -1.778 -1.45796)
			(stroke
				(width 0.1)
				(type default)
			)
			(layer "F.SilkS")
		)
		(fp_line
			(start 1.778 -1.778)
			(end -1.778 -1.778)
			(stroke
				(width 0.1)
				(type default)
			)
			(layer "F.SilkS")
		)
		(fp_poly
			(pts
				(arc
					(start -3.730498 -1.372362)
					(mid -3.730498 -0.610362)
					(end -3.730498 -1.372362)
				)
			)
			(stroke
				(width 0)
				(type default)
			)
			(fill yes)
			(layer "F.SilkS")
		)
		(fp_poly
			(pts
				(xy -3.5687 -2.032) (xy -3.5687 2.032) (xy 3.5687 2.032) (xy 3.5687 -2.032)
			)
			(stroke
				(width 0)
				(type default)
			)
			(fill no)
			(layer "F.CrtYd")
		)
		(fp_line
			(start -1.524 1.524)
			(end -1.524 -1.524)
			(stroke
				(width 0.1)
				(type default)
			)
			(layer "F.Fab")
		)
		(fp_line
			(start 1.524 1.524)
			(end -1.524 1.524)
			(stroke
				(width 0.1)
				(type default)
			)
			(layer "F.Fab")
		)
		(fp_line
			(start -1.524 -1.524)
			(end 1.524 -1.524)
			(stroke
				(width 0.1)
				(type default)
			)
			(layer "F.Fab")
		)
		(fp_line
			(start 1.524 -1.524)
			(end 1.524 1.524)
			(stroke
				(width 0.1)
				(type default)
			)
			(layer "F.Fab")
		)
		(fp_poly
			(pts
				(arc
					(start -0.9906 -1.3208)
					(mid -0.9906 -0.5588)
					(end -0.9906 -1.3208)
				)
			)
			(stroke
				(width 0)
				(type default)
			)
			(fill yes)
			(layer "F.Fab")
		)
		(fp_text user "5"
			(at 3.91795 1.905 0)
			(unlocked yes)
			(layer "F.SilkS")
			(effects
				(font
					(size 0.635 0.4064)
					(thickness 0.1524)
				)
			)
		)
		(fp_text user "4"
			(at -4.08305 1.778 0)
			(unlocked yes)
			(layer "F.SilkS")
			(effects
				(font
					(size 0.635 0.4064)
					(thickness 0.1524)
				)
			)
		)
		(fp_text user "8"
			(at 3.40995 -2.413 0)
			(unlocked yes)
			(layer "F.SilkS")
			(effects
				(font
					(size 0.635 0.4064)
					(thickness 0.1524)
				)
			)
		)
		(fp_text user "5"
			(at 3.21437 1.651 0)
			(unlocked yes)
			(layer "F.Fab")
			(effects
				(font
					(size 0.7874 0.5842)
					(thickness 0.1524)
				)
			)
		)
		(fp_text user "4"
			(at -3.26263 1.524 0)
			(unlocked yes)
			(layer "F.Fab")
			(effects
				(font
					(size 0.7874 0.5842)
					(thickness 0.1524)
				)
			)
		)
		(fp_text user "8"
			(at 3.21437 -1.905 0)
			(unlocked yes)
			(layer "F.Fab")
			(effects
				(font
					(size 0.7874 0.5842)
					(thickness 0.1524)
				)
			)
		)
		(pad "1" smd rect
			(at -2.2987 -0.97536)
			(size 0.4572 1.524)
			(layers "F.Cu" "F.Mask" "F.Paste")
			(net "R_LM75B_2_I2C_SDA")
		)
		(pad "2" smd rect
			(at -2.2987 -0.32512)
			(size 0.4572 1.524)
			(layers "F.Cu" "F.Mask" "F.Paste")
			(net "LM75B_I2C_SCL")
		)
		(pad "3" smd rect
			(at -2.2987 0.32512)
			(size 0.4572 1.524)
			(layers "F.Cu" "F.Mask" "F.Paste")
			(net "FPGA_IN_LM75B_INT2_N")
		)
		(pad "4" smd rect
			(at -2.2987 0.97536)
			(size 0.4572 1.524)
			(layers "F.Cu" "F.Mask" "F.Paste")
			(net "SG")
		)
		(pad "5" smd rect
			(at 2.2987 0.97536)
			(size 0.4572 1.524)
			(layers "F.Cu" "F.Mask" "F.Paste")
			(net "UNNAMED_6_LM75BDPTSSOP8_I59_A2")
		)
		(pad "6" smd rect
			(at 2.2987 0.32512)
			(size 0.4572 1.524)
			(layers "F.Cu" "F.Mask" "F.Paste")
			(net "UNNAMED_6_LM75BDPTSSOP8_I59_A1")
		)
		(pad "7" smd rect
			(at 2.2987 -0.32512)
			(size 0.4572 1.524)
			(layers "F.Cu" "F.Mask" "F.Paste")
			(net "UNNAMED_6_LM75BDPTSSOP8_I59_A0")
		)
		(pad "8" smd rect
			(at 2.2987 -0.97536)
			(size 0.4572 1.524)
			(layers "F.Cu" "F.Mask" "F.Paste")
			(net "XP3R3V_FPGA")
		)
	)
	(footprint ""
		(layer "F.Cu")
		(at 95.25 -53.34)
		(property "Reference" "TP181"
			(at 0 0 0)
			(layer "F.SilkS")
			(hide yes)
			(effects
				(font
					(size 1.27 1.27)
				)
			)
		)
		(property "Value" ""
			(at 0 0 0)
			(layer "F.Fab")
			(effects
				(font
					(size 1.27 1.27)
				)
			)
		)
		(property "Device Type" "TP_PIONT-TP010CT020B030_PTH-TPA"
			(at -1.341882 0.996696 0)
			(unlocked yes)
			(layer "F.Fab")
			(hide yes)
			(effects
				(font
					(size 0.7874 0.5842)
					(thickness 0.1524)
				)
				(justify left)
			)
		)
		(duplicate_pad_numbers_are_jumpers no)
		(fp_poly
			(pts
				(arc
					(start 0.889 0)
					(mid -0.889 0)
					(end 0.889 0)
				)
			)
			(stroke
				(width 0)
				(type default)
			)
			(fill no)
			(layer "B.CrtYd")
		)
		(fp_poly
			(pts
				(arc
					(start 0.889 0)
					(mid -0.889 0)
					(end 0.889 0)
				)
			)
			(stroke
				(width 0)
				(type default)
			)
			(fill no)
			(layer "F.CrtYd")
		)
		(pad "1" thru_hole circle
			(at 0 0)
			(size 0.508 0.508)
			(drill 0.254)
			(layers "*.Cu" "*.Mask")
			(remove_unused_layers no)
			(net "IO_L21P_16")
			(clearance 0.1016)
			(padstack
				(mode front_inner_back)
				(layer "Inner"
					(shape circle)
					(size 0.508 0.508)
					(clearance 0.1016)
				)
				(layer "B.Cu"
					(shape circle)
					(size 0.762 0.762)
					(clearance -0.0254)
				)
			)
		)
	)
	(footprint ""
		(layer "F.Cu")
		(at 11.557 -44.704 90)
		(property "Reference" "R126"
			(at 0.508 -1.23063 90)
			(unlocked yes)
			(layer "F.SilkS")
			(effects
				(font
					(size 0.7874 0.5842)
					(thickness 0.1524)
				)
			)
		)
		(property "Value" "VAL*"
			(at 0.02032 2.13233 90)
			(unlocked yes)
			(layer "F.Fab")
			(hide yes)
			(effects
				(font
					(size 0.7874 0.5842)
					(thickness 0.1524)
				)
			)
		)
		(property "Tolerance" "TOL*"
			(at 0.044704 3.05435 90)
			(unlocked yes)
			(layer "Cmts.User")
			(hide yes)
			(effects
				(font
					(size 0.7874 0.5842)
					(thickness 0.1524)
				)
			)
		)
		(property "User Part Number" "PARTNUM*"
			(at 0.02032 4.024884 90)
			(unlocked yes)
			(layer "Cmts.User")
			(hide yes)
			(effects
				(font
					(size 0.7874 0.5842)
					(thickness 0.1524)
				)
			)
		)
		(property "Device Type" "RESISTOR-G155-149R9-01,49.9OHMA"
			(at 0.008382 1.210564 90)
			(unlocked yes)
			(layer "F.Fab")
			(hide yes)
			(effects
				(font
					(size 0.7874 0.5842)
					(thickness 0.1524)
				)
			)
		)
		(duplicate_pad_numbers_are_jumpers no)
		(fp_line
			(start 1.143 -0.5588)
			(end -1.143 -0.5588)
			(stroke
				(width 0.1)
				(type default)
			)
			(layer "F.SilkS")
		)
		(fp_line
			(start -1.143 -0.5588)
			(end -1.143 0.5588)
			(stroke
				(width 0.1)
				(type default)
			)
			(layer "F.SilkS")
		)
		(fp_line
			(start 1.143 0.5588)
			(end 1.143 -0.5588)
			(stroke
				(width 0.1)
				(type default)
			)
			(layer "F.SilkS")
		)
		(fp_line
			(start -1.143 0.5588)
			(end 1.143 0.5588)
			(stroke
				(width 0.1)
				(type default)
			)
			(layer "F.SilkS")
		)
		(fp_poly
			(pts
				(xy -1.143 0.5588) (xy 1.143 0.5588) (xy 1.143 -0.5588) (xy -1.143 -0.5588)
			)
			(stroke
				(width 0)
				(type default)
			)
			(fill no)
			(layer "F.CrtYd")
		)
		(fp_line
			(start 0.508 -0.3048)
			(end -0.508 -0.3048)
			(stroke
				(width 0.1)
				(type default)
			)
			(layer "F.Fab")
		)
		(fp_line
			(start -0.508 -0.3048)
			(end -0.508 0.3048)
			(stroke
				(width 0.1)
				(type default)
			)
			(layer "F.Fab")
		)
		(fp_line
			(start 0.508 0.3048)
			(end 0.508 -0.3048)
			(stroke
				(width 0.1)
				(type default)
			)
			(layer "F.Fab")
		)
		(fp_line
			(start -0.508 0.3048)
			(end 0.508 0.3048)
			(stroke
				(width 0.1)
				(type default)
			)
			(layer "F.Fab")
		)
		(pad "1" smd rect
			(at -0.5334 0 90)
			(size 0.7112 0.6096)
			(layers "F.Cu" "F.Mask" "F.Paste")
			(net "BF_SMA2_SIG_IO_CONN")
		)
		(pad "2" smd rect
			(at 0.5334 0 90)
			(size 0.7112 0.6096)
			(layers "F.Cu" "F.Mask" "F.Paste")
			(net "SMA2_SIG_IO_CONN")
		)
		(zone
			(layer "F.Cu")
			(hatch none 0.5)
			(connect_pads
				(clearance 0)
			)
			(min_thickness 0.25)
			(keepout
				(tracks allowed)
				(vias not_allowed)
				(pads allowed)
				(copperpour not_allowed)
				(footprints allowed)
			)
			(placement
				(enabled no)
				(sheetname "")
			)
			(fill
				(thermal_gap 0.5)
				(thermal_bridge_width 0.5)
				(island_removal_mode 0)
			)
			(polygon
				(pts
					(xy 11.8618 -44.6278) (xy 11.8618 -44.7802) (xy 11.2522 -44.7802) (xy 11.2522 -44.6278)
				)
			)
		)
		(zone
			(layer "F.Cu")
			(hatch none 0.5)
			(connect_pads
				(clearance 0)
			)
			(min_thickness 0.25)
			(keepout
				(tracks not_allowed)
				(vias allowed)
				(pads allowed)
				(copperpour not_allowed)
				(footprints allowed)
			)
			(placement
				(enabled no)
				(sheetname "")
			)
			(fill
				(thermal_gap 0.5)
				(thermal_bridge_width 0.5)
				(island_removal_mode 0)
			)
			(polygon
				(pts
					(xy 11.8618 -44.6278) (xy 11.8618 -44.7802) (xy 11.2522 -44.7802) (xy 11.2522 -44.6278)
				)
			)
		)
	)
	(footprint ""
		(layer "F.Cu")
		(at 161.04997 -89.149936 -90)
		(property "Reference" "P3"
			(at -8.232394 -0.36703 0)
			(unlocked yes)
			(layer "F.SilkS")
			(effects
				(font
					(size 0.7874 0.5842)
					(thickness 0.1524)
				)
			)
		)
		(property "Value" ""
			(at 0 0 270)
			(layer "F.Fab")
			(effects
				(font
					(size 1.27 1.27)
				)
			)
		)
		(property "Device Type" "CONN_HDR_2X3_M_RA_TH-G200-1251A"
			(at 0 14.183868 270)
			(unlocked yes)
			(layer "F.Fab")
			(hide yes)
			(effects
				(font
					(size 0.7874 0.5842)
					(thickness 0.1524)
				)
			)
		)
		(property "User Part Number" "PARTNUM*"
			(at 0 15.377668 270)
			(unlocked yes)
			(layer "Cmts.User")
			(hide yes)
			(effects
				(font
					(size 0.7874 0.5842)
					(thickness 0.1524)
				)
			)
		)
		(duplicate_pad_numbers_are_jumpers no)
		(fp_line
			(start -7.343902 13.074904)
			(end -7.343902 -7.043928)
			(stroke
				(width 0.1)
				(type default)
			)
			(layer "F.SilkS")
		)
		(fp_line
			(start 7.343902 13.074904)
			(end -7.343902 13.074904)
			(stroke
				(width 0.1)
				(type default)
			)
			(layer "F.SilkS")
		)
		(fp_line
			(start -7.343902 -7.043928)
			(end 7.343902 -7.043928)
			(stroke
				(width 0.1)
				(type default)
			)
			(layer "F.SilkS")
		)
		(fp_line
			(start 7.343902 -7.043928)
			(end 7.343902 13.074904)
			(stroke
				(width 0.1)
				(type default)
			)
			(layer "F.SilkS")
		)
		(fp_rect
			(start 10.60069 17.900904)
			(end -10.60069 0.89916)
			(stroke
				(width 0)
				(type default)
			)
			(fill no)
			(layer "B.CrtYd")
		)
		(fp_rect
			(start 7.597902 13.328904)
			(end -7.597902 -7.297928)
			(stroke
				(width 0)
				(type default)
			)
			(fill no)
			(layer "F.CrtYd")
		)
		(fp_line
			(start -7.089902 6.389878)
			(end -7.089902 -6.789928)
			(stroke
				(width 0.1)
				(type default)
			)
			(layer "F.Fab")
		)
		(fp_line
			(start 7.089902 6.389878)
			(end -7.089902 6.389878)
			(stroke
				(width 0.1)
				(type default)
			)
			(layer "F.Fab")
		)
		(fp_line
			(start -7.089902 -6.789928)
			(end 7.089902 -6.789928)
			(stroke
				(width 0.1)
				(type default)
			)
			(layer "F.Fab")
		)
		(fp_line
			(start 7.089902 -6.789928)
			(end 7.089902 6.389878)
			(stroke
				(width 0.1)
				(type default)
			)
			(layer "F.Fab")
		)
		(fp_text user "4"
			(at -8.092694 11.06297 0)
			(unlocked yes)
			(layer "F.SilkS")
			(effects
				(font
					(size 0.7874 0.5842)
					(thickness 0.1524)
				)
			)
		)
		(fp_text user "6"
			(at 8.163306 9.53897 0)
			(unlocked yes)
			(layer "F.SilkS")
			(effects
				(font
					(size 0.7874 0.5842)
					(thickness 0.1524)
				)
			)
		)
		(fp_text user "1"
			(at -7.965694 6.49097 0)
			(unlocked yes)
			(layer "F.SilkS")
			(effects
				(font
					(size 0.7874 0.5842)
					(thickness 0.1524)
				)
			)
		)
		(fp_text user "3"
			(at 8.036306 5.98297 0)
			(unlocked yes)
			(layer "F.SilkS")
			(effects
				(font
					(size 0.7874 0.5842)
					(thickness 0.1524)
				)
			)
		)
		(fp_text user "6"
			(at 6.996176 11.553444 0)
			(unlocked yes)
			(layer "F.Fab")
			(effects
				(font
					(size 0.7874 0.5842)
					(thickness 0.1524)
				)
			)
		)
		(fp_text user "4"
			(at -7.671308 11.30173 0)
			(unlocked yes)
			(layer "F.Fab")
			(effects
				(font
					(size 0.7874 0.5842)
					(thickness 0.1524)
				)
			)
		)
		(fp_text user "3"
			(at 7.120636 7.170674 0)
			(unlocked yes)
			(layer "F.Fab")
			(effects
				(font
					(size 0.7874 0.5842)
					(thickness 0.1524)
				)
			)
		)
		(fp_text user "1"
			(at -7.515606 6.825742 0)
			(unlocked yes)
			(layer "F.Fab")
			(effects
				(font
					(size 0.7874 0.5842)
					(thickness 0.1524)
				)
			)
		)
		(pad "" np_thru_hole circle
			(at -4.19989 0 270)
			(size 2.7432 2.7432)
			(drill 2.9972)
			(layers "*.Cu" "*.Mask")
			(padstack
				(mode front_inner_back)
				(layer "Inner"
					(shape circle)
					(size 2.7432 2.7432)
					(clearance 0.4445)
				)
				(layer "B.Cu"
					(shape circle)
					(size 2.7432 2.7432)
				)
			)
		)
		(pad "" np_thru_hole circle
			(at 4.19989 0 270)
			(size 2.7432 2.7432)
			(drill 2.9972)
			(layers "*.Cu" "*.Mask")
			(padstack
				(mode front_inner_back)
				(layer "Inner"
					(shape circle)
					(size 2.7432 2.7432)
					(clearance 0.4445)
				)
				(layer "B.Cu"
					(shape circle)
					(size 2.7432 2.7432)
				)
			)
		)
		(pad "1" thru_hole rect
			(at -4.19989 7.29996 270)
			(size 2.6416 2.6416)
			(drill 1.9304)
			(layers "*.Cu" "*.Mask")
			(remove_unused_layers no)
			(net "XP12R0V_EXT")
			(padstack
				(mode front_inner_back)
				(layer "Inner"
					(shape circle)
					(size 2.6416 2.6416)
					(clearance -0.0635)
				)
				(layer "B.Cu"
					(shape rect)
					(size 2.6416 2.6416)
				)
			)
		)
		(pad "2" thru_hole circle
			(at 0 7.29996 270)
			(size 2.6416 2.6416)
			(drill 1.9304)
			(layers "*.Cu" "*.Mask")
			(remove_unused_layers no)
			(net "XP12R0V_EXT")
			(padstack
				(mode front_inner_back)
				(layer "Inner"
					(shape circle)
					(size 2.6416 2.6416)
					(clearance -0.0635)
				)
				(layer "B.Cu"
					(shape circle)
					(size 2.6416 2.6416)
				)
			)
		)
		(pad "3" thru_hole circle
			(at 4.19989 7.29996 270)
			(size 2.6416 2.6416)
			(drill 1.9304)
			(layers "*.Cu" "*.Mask")
			(remove_unused_layers no)
			(net "XP12R0V_EXT")
			(padstack
				(mode front_inner_back)
				(layer "Inner"
					(shape circle)
					(size 2.6416 2.6416)
					(clearance -0.0635)
				)
				(layer "B.Cu"
					(shape circle)
					(size 2.6416 2.6416)
				)
			)
		)
		(pad "4" thru_hole circle
			(at -4.19989 11.500104 270)
			(size 2.6416 2.6416)
			(drill 1.9304)
			(layers "*.Cu" "*.Mask")
			(remove_unused_layers no)
			(net "SG")
			(padstack
				(mode front_inner_back)
				(layer "Inner"
					(shape circle)
					(size 2.6416 2.6416)
					(clearance -0.0635)
				)
				(layer "B.Cu"
					(shape circle)
					(size 2.6416 2.6416)
				)
			)
		)
		(pad "5" thru_hole circle
			(at 0 11.500104 270)
			(size 2.6416 2.6416)
			(drill 1.9304)
			(layers "*.Cu" "*.Mask")
			(remove_unused_layers no)
			(net "SG")
			(padstack
				(mode front_inner_back)
				(layer "Inner"
					(shape circle)
					(size 2.6416 2.6416)
					(clearance -0.0635)
				)
				(layer "B.Cu"
					(shape circle)
					(size 2.6416 2.6416)
				)
			)
		)
		(pad "6" thru_hole circle
			(at 4.19989 11.500104 270)
			(size 2.6416 2.6416)
			(drill 1.9304)
			(layers "*.Cu" "*.Mask")
			(remove_unused_layers no)
			(net "SG")
			(padstack
				(mode front_inner_back)
				(layer "Inner"
					(shape circle)
					(size 2.6416 2.6416)
					(clearance -0.0635)
				)
				(layer "B.Cu"
					(shape circle)
					(size 2.6416 2.6416)
				)
			)
		)
		(zone
			(layers "F.Cu" "B.Cu" "In1.Cu" "In2.Cu" "In3.Cu" "In4.Cu" "In5.Cu" "In6.Cu"
				"In7.Cu" "In8.Cu"
			)
			(hatch none 0.5)
			(connect_pads
				(clearance 0)
			)
			(min_thickness 0.25)
			(keepout
				(tracks not_allowed)
				(vias allowed)
				(pads allowed)
				(copperpour not_allowed)
				(footprints allowed)
			)
			(placement
				(enabled no)
				(sheetname "")
			)
			(fill
				(thermal_gap 0.5)
				(thermal_bridge_width 0.5)
				(island_removal_mode 0)
			)
			(polygon
				(pts
					(arc
						(start 163.18357 -93.349826)
						(mid 158.91637 -93.349826)
						(end 163.18357 -93.349826)
					)
				)
			)
		)
		(zone
			(layers "F.Cu" "B.Cu" "In1.Cu" "In2.Cu" "In3.Cu" "In4.Cu" "In5.Cu" "In6.Cu"
				"In7.Cu" "In8.Cu"
			)
			(hatch none 0.5)
			(connect_pads
				(clearance 0)
			)
			(min_thickness 0.25)
			(keepout
				(tracks not_allowed)
				(vias allowed)
				(pads allowed)
				(copperpour not_allowed)
				(footprints allowed)
			)
			(placement
				(enabled no)
				(sheetname "")
			)
			(fill
				(thermal_gap 0.5)
				(thermal_bridge_width 0.5)
				(island_removal_mode 0)
			)
			(polygon
				(pts
					(arc
						(start 163.18357 -84.950046)
						(mid 158.91637 -84.950046)
						(end 163.18357 -84.950046)
					)
				)
			)
		)
	)
)
